# T6G (Grand Teton) — schematic netlist excerpt (pin names and nets, part order shuffled) for the footprints in the layout excerpt that follows; sources: Cadence DE-HDL packaged netlist, KiCad conversion of 04192023_DAF0TMB3IC0_F0TG_MB_C_brd_V02_OCP.brd

PC129  Q_CAP  22UF 16V 20% X6S  pkg C0805  page 192 : A = PVDD_33_S5 ; B = GND
C1836  Q_CAP  0.1UF 25V 10% X7R  pkg 0402  page 137 : A = P3V3_OCP_V3_2 ; B = GND
C222  Q_CAP  1UF 4V 20% X6S  pkg 0201  page 323 : A = P0V9_CPU1_RT0_2A ; B = GND

(kicad_pcb
	(version 20260206)
	(generator "pcbnew")
	(generator_version "10.0")
	(general
		(thickness 1.6)
		(legacy_teardrops no)
	)
	(paper "A4")
	(title_block
		(title "04192023_DAF0TMB3IC0_F0TG_MB_C_brd_V02_OCP.brd")
		(comment 1 "Grand Teton / footprints 7426-7428 of 8354")
	)
	(layers
		(0 "F.Cu" signal "TOP")
		(4 "In1.Cu" signal "GND")
		(6 "In2.Cu" signal "IN1")
		(8 "In3.Cu" signal "GND1")
		(10 "In4.Cu" signal "IN2")
		(12 "In5.Cu" signal "GND2")
		(14 "In6.Cu" signal "IN3")
		(16 "In7.Cu" signal "GND3")
		(18 "In8.Cu" signal "VCC")
		(20 "In9.Cu" signal "VCC1")
		(22 "In10.Cu" signal "GND4")
		(24 "In11.Cu" signal "IN4")
		(26 "In12.Cu" signal "GND5")
		(28 "In13.Cu" signal "IN5")
		(30 "In14.Cu" signal "GND6")
		(32 "In15.Cu" signal "IN6")
		(34 "In16.Cu" signal "GND7")
		(2 "B.Cu" signal "BOTTOM")
		(9 "F.Adhes" user "F.Adhesive")
		(11 "B.Adhes" user "B.Adhesive")
		(13 "F.Paste" user "Package Geometry/Pastemask Top")
		(15 "B.Paste" user "Package Geometry/Pastemask Bottom")
		(5 "F.SilkS" user "Ref Des/Silkscreen Top")
		(7 "B.SilkS" user "Ref Des/Silkscreen Bottom")
		(1 "F.Mask" user "Board Geometry/Soldermask Top")
		(3 "B.Mask" user "Board Geometry/Soldermask Bottom")
		(17 "Dwgs.User" user "User.Drawings")
		(19 "Cmts.User" user "User.Comments")
		(21 "Eco1.User" user "User.Eco1")
		(23 "Eco2.User" user "User.Eco2")
		(25 "Edge.Cuts" user "Board Geometry/Outline")
		(27 "Margin" user)
		(31 "F.CrtYd" user "Package Geometry/Place Bound Top")
		(29 "B.CrtYd" user "Package Geometry/Place Bound Bottom")
		(35 "F.Fab" user "Ref Des/Assembly Top")
		(33 "B.Fab" user "Ref Des/Assembly Bottom")
	)
	(footprint ""
		(layer "B.Cu")
		(at 62.978538 -386.766562 90)
		(property "Reference" "C222"
			(at 0 0 90)
			(layer "B.SilkS")
			(hide yes)
			(effects
				(font
					(size 1.27 1.27)
				)
				(justify mirror)
			)
		)
		(property "Value" ""
			(at 0 0 90)
			(layer "B.Fab")
			(effects
				(font
					(size 1.27 1.27)
				)
				(justify mirror)
			)
		)
		(duplicate_pad_numbers_are_jumpers no)
		(fp_line
			(start 0.299974 -0.150114)
			(end -0.299974 -0.150114)
			(stroke
				(width 0.1)
				(type default)
			)
			(layer "B.Fab")
		)
		(fp_line
			(start -0.299974 -0.150114)
			(end -0.299974 0.150114)
			(stroke
				(width 0.1)
				(type default)
			)
			(layer "B.Fab")
		)
		(fp_line
			(start 0.299974 0.150114)
			(end 0.299974 -0.150114)
			(stroke
				(width 0.1)
				(type default)
			)
			(layer "B.Fab")
		)
		(fp_line
			(start -0.299974 0.150114)
			(end 0.299974 0.150114)
			(stroke
				(width 0.1)
				(type default)
			)
			(layer "B.Fab")
		)
		(pad "1" smd rect
			(at 0.2667 0 270)
			(size 0.3048 0.381)
			(layers "B.Cu" "B.Mask" "B.Paste")
			(net "P0V9_CPU1_RT0_2A")
		)
		(pad "2" smd rect
			(at -0.2667 0 270)
			(size 0.3048 0.381)
			(layers "B.Cu" "B.Mask" "B.Paste")
			(net "GND")
		)
	)
	(footprint ""
		(layer "B.Cu")
		(at 61.52388 -8.981948 90)
		(property "Reference" "C1836"
			(at 0 0 90)
			(layer "B.SilkS")
			(hide yes)
			(effects
				(font
					(size 1.27 1.27)
				)
				(justify mirror)
			)
		)
		(property "Value" ""
			(at 0 0 90)
			(layer "B.Fab")
			(effects
				(font
					(size 1.27 1.27)
				)
				(justify mirror)
			)
		)
		(duplicate_pad_numbers_are_jumpers no)
		(fp_line
			(start 0.7874 -0.4064)
			(end -0.7874 -0.4064)
			(stroke
				(width 0.1524)
				(type default)
			)
			(layer "B.SilkS")
		)
		(fp_line
			(start -0.7874 -0.4064)
			(end -0.7874 0.4064)
			(stroke
				(width 0.1524)
				(type default)
			)
			(layer "B.SilkS")
		)
		(fp_line
			(start 0.7874 0.4064)
			(end 0.7874 -0.4064)
			(stroke
				(width 0.1524)
				(type default)
			)
			(layer "B.SilkS")
		)
		(fp_line
			(start -0.7874 0.4064)
			(end 0.7874 0.4064)
			(stroke
				(width 0.1524)
				(type default)
			)
			(layer "B.SilkS")
		)
		(fp_line
			(start 0.67945 -0.305054)
			(end 0.12065 -0.305054)
			(stroke
				(width 0.1)
				(type default)
			)
			(layer "B.Fab")
		)
		(fp_line
			(start 0.12065 -0.305054)
			(end 0.12065 -0.2794)
			(stroke
				(width 0.1)
				(type default)
			)
			(layer "B.Fab")
		)
		(fp_line
			(start -0.12065 -0.3048)
			(end -0.67945 -0.3048)
			(stroke
				(width 0.1)
				(type default)
			)
			(layer "B.Fab")
		)
		(fp_line
			(start -0.67945 -0.3048)
			(end -0.67945 0.3048)
			(stroke
				(width 0.1)
				(type default)
			)
			(layer "B.Fab")
		)
		(fp_line
			(start 0.12065 -0.2794)
			(end -0.12065 -0.2794)
			(stroke
				(width 0.1)
				(type default)
			)
			(layer "B.Fab")
		)
		(fp_line
			(start -0.12065 -0.2794)
			(end -0.12065 -0.3048)
			(stroke
				(width 0.1)
				(type default)
			)
			(layer "B.Fab")
		)
		(fp_line
			(start 0.12065 0.2794)
			(end 0.12065 0.3048)
			(stroke
				(width 0.1)
				(type default)
			)
			(layer "B.Fab")
		)
		(fp_line
			(start -0.120396 0.2794)
			(end 0.12065 0.2794)
			(stroke
				(width 0.1)
				(type default)
			)
			(layer "B.Fab")
		)
		(fp_line
			(start 0.67945 0.3048)
			(end 0.67945 -0.305054)
			(stroke
				(width 0.1)
				(type default)
			)
			(layer "B.Fab")
		)
		(fp_line
			(start 0.12065 0.3048)
			(end 0.67945 0.3048)
			(stroke
				(width 0.1)
				(type default)
			)
			(layer "B.Fab")
		)
		(fp_line
			(start -0.120396 0.3048)
			(end -0.120396 0.2794)
			(stroke
				(width 0.1)
				(type default)
			)
			(layer "B.Fab")
		)
		(fp_line
			(start -0.67945 0.3048)
			(end -0.120396 0.3048)
			(stroke
				(width 0.1)
				(type default)
			)
			(layer "B.Fab")
		)
		(pad "1" smd circle
			(at 0.40005 0 270)
			(size 0 0)
			(layers "B.Cu" "B.Mask" "B.Paste")
			(net "P3V3_OCP_V3_2")
		)
		(pad "2" smd circle
			(at -0.40005 0 270)
			(size 0 0)
			(layers "B.Cu" "B.Mask" "B.Paste")
			(net "GND")
		)
	)
	(footprint ""
		(layer "B.Cu")
		(at 199.96912 -331.027786 -90)
		(property "Reference" "PC129"
			(at 0 0 90)
			(layer "B.SilkS")
			(hide yes)
			(effects
				(font
					(size 1.27 1.27)
				)
				(justify mirror)
			)
		)
		(property "Value" ""
			(at 0 0 90)
			(layer "B.Fab")
			(effects
				(font
					(size 1.27 1.27)
				)
				(justify mirror)
			)
		)
		(duplicate_pad_numbers_are_jumpers no)
		(fp_line
			(start -1.524 0.762)
			(end 1.524 0.762)
			(stroke
				(width 0.1524)
				(type default)
			)
			(layer "B.SilkS")
		)
		(fp_line
			(start 1.524 0.762)
			(end 1.524 -0.762)
			(stroke
				(width 0.1524)
				(type default)
			)
			(layer "B.SilkS")
		)
		(fp_line
			(start -1.524 -0.762)
			(end -1.524 0.762)
			(stroke
				(width 0.1524)
				(type default)
			)
			(layer "B.SilkS")
		)
		(fp_line
			(start 1.524 -0.762)
			(end -1.524 -0.762)
			(stroke
				(width 0.1524)
				(type default)
			)
			(layer "B.SilkS")
		)
		(fp_line
			(start -1.1049 0.724916)
			(end -1.1049 -0.724916)
			(stroke
				(width 0.1)
				(type default)
			)
			(layer "B.Fab")
		)
		(fp_line
			(start 1.1049 0.724916)
			(end -1.1049 0.724916)
			(stroke
				(width 0.1)
				(type default)
			)
			(layer "B.Fab")
		)
		(fp_line
			(start -1.1049 -0.724916)
			(end 1.1049 -0.724916)
			(stroke
				(width 0.1)
				(type default)
			)
			(layer "B.Fab")
		)
		(fp_line
			(start 1.1049 -0.724916)
			(end 1.1049 0.724916)
			(stroke
				(width 0.1)
				(type default)
			)
			(layer "B.Fab")
		)
		(pad "1" smd rect
			(at 0.889 0 270)
			(size 1.016 1.27)
			(layers "B.Cu" "B.Mask" "B.Paste")
			(net "PVDD_33_S5")
		)
		(pad "2" smd rect
			(at -0.889 0 270)
			(size 1.016 1.27)
			(layers "B.Cu" "B.Mask" "B.Paste")
			(net "GND")
		)
	)
)
